(kicad_pcb
	(version 20260206)
	(generator "pcbnew")
	(generator_version "10.0")
	(general
		(thickness 1.6)
		(legacy_teardrops no)
	)
	(paper "A4")
	(title_block
		(title "baseboard — 13948-1b.1110WZS1818.brd")
		(comment 1 "Honey Badger (Wiwynn) / footprints 955-961 of 2523")
	)
	(layers
		(0 "F.Cu" signal "TOP")
		(4 "In1.Cu" signal "L2GND")
		(6 "In2.Cu" signal "L3")
		(8 "In3.Cu" signal "L4VCC")
		(10 "In4.Cu" signal "L5VCC")
		(12 "In5.Cu" signal "L6")
		(14 "In6.Cu" signal "L7GND")
		(2 "B.Cu" signal "BOTTOM")
		(9 "F.Adhes" user "F.Adhesive")
		(11 "B.Adhes" user "B.Adhesive")
		(13 "F.Paste" user "Package Geometry/Pastemask Top")
		(15 "B.Paste" user "Package Geometry/Pastemask Bottom")
		(5 "F.SilkS" user "Ref Des/Silkscreen Top")
		(7 "B.SilkS" user "Ref Des/Silkscreen Bottom")
		(1 "F.Mask" user "Board Geometry/Soldermask Top")
		(3 "B.Mask" user "Board Geometry/Soldermask Bottom")
		(17 "Dwgs.User" user "User.Drawings")
		(19 "Cmts.User" user "User.Comments")
		(21 "Eco1.User" user "User.Eco1")
		(23 "Eco2.User" user "User.Eco2")
		(25 "Edge.Cuts" user "Board Geometry/Outline")
		(27 "Margin" user)
		(31 "F.CrtYd" user "Package Geometry/Place Bound Top")
		(29 "B.CrtYd" user "Package Geometry/Place Bound Bottom")
		(35 "F.Fab" user "Ref Des/Assembly Top")
		(33 "B.Fab" user "Ref Des/Assembly Bottom")
	)
	(footprint ""
		(layer "F.Cu")
		(at 60.706 -106.426 -90)
		(property "Reference" "SR821"
			(at 0 0 270)
			(layer "F.SilkS")
			(hide yes)
			(effects
				(font
					(size 1.27 1.27)
				)
			)
		)
		(property "Value" "4K75R2F-1-GP"
			(at 0.064008 -3.993896 270)
			(unlocked yes)
			(layer "F.Fab")
			(hide yes)
			(effects
				(font
					(size 1.016 1.016)
					(thickness 0.1524)
				)
			)
		)
		(property "Device Type" "R402H16"
			(at 0.064008 -5.517896 270)
			(unlocked yes)
			(layer "F.Fab")
			(hide yes)
			(effects
				(font
					(size 1.016 1.016)
					(thickness 0.1524)
				)
			)
		)
		(duplicate_pad_numbers_are_jumpers no)
		(fp_line
			(start -0.508 -0.9398)
			(end -0.508 0.9398)
			(stroke
				(width 0.1524)
				(type default)
			)
			(layer "F.SilkS")
		)
		(fp_line
			(start 0.508 -0.9398)
			(end -0.508 -0.9398)
			(stroke
				(width 0.1524)
				(type default)
			)
			(layer "F.SilkS")
		)
		(fp_rect
			(start -0.508 0.9398)
			(end 0.508 -0.9398)
			(stroke
				(width 0)
				(type default)
			)
			(fill no)
			(layer "F.CrtYd")
		)
		(fp_rect
			(start -0.508 0.9398)
			(end 0.508 -0.9398)
			(stroke
				(width 0)
				(type default)
			)
			(fill no)
			(layer "F.Fab")
		)
		(pad "1" smd custom
			(at 0 -0.4445 270)
			(size 0.1397 0.1397)
			(layers "F.Cu" "F.Mask" "F.Paste")
			(net "EXP_FW_DET_BOARD_VER_2")
			(options
				(clearance outline)
				(anchor circle)
			)
			(primitives
				(gr_poly
					(pts
						(arc
							(start -0.1778 -0.2794)
							(mid -0.249642 -0.249642)
							(end -0.2794 -0.1778)
						)
						(arc
							(start -0.2794 0.1778)
							(mid -0.249642 0.249642)
							(end -0.1778 0.2794)
						)
						(arc
							(start 0.1778 0.2794)
							(mid 0.249642 0.249642)
							(end 0.2794 0.1778)
						)
						(arc
							(start 0.2794 -0.1778)
							(mid 0.249642 -0.249642)
							(end 0.1778 -0.2794)
						)
					)
					(width 0)
					(fill yes)
				)
			)
		)
		(pad "2" smd custom
			(at 0 0.4445 270)
			(size 0.1397 0.1397)
			(layers "F.Cu" "F.Mask" "F.Paste")
			(net "GND")
			(options
				(clearance outline)
				(anchor circle)
			)
			(primitives
				(gr_poly
					(pts
						(arc
							(start -0.1778 -0.2794)
							(mid -0.249642 -0.249642)
							(end -0.2794 -0.1778)
						)
						(arc
							(start -0.2794 0.1778)
							(mid -0.249642 0.249642)
							(end -0.1778 0.2794)
						)
						(arc
							(start 0.1778 0.2794)
							(mid 0.249642 0.249642)
							(end 0.2794 0.1778)
						)
						(arc
							(start 0.2794 -0.1778)
							(mid 0.249642 -0.249642)
							(end 0.1778 -0.2794)
						)
					)
					(width 0)
					(fill yes)
				)
			)
		)
	)
	(footprint ""
		(layer "F.Cu")
		(at 333.912718 -147.805648 90)
		(property "Reference" "R552"
			(at 0 0 90)
			(layer "F.SilkS")
			(hide yes)
			(effects
				(font
					(size 1.27 1.27)
				)
			)
		)
		(property "Value" "4K7R2F-GP"
			(at 0.064008 -3.993896 90)
			(unlocked yes)
			(layer "F.Fab")
			(hide yes)
			(effects
				(font
					(size 1.016 1.016)
					(thickness 0.1524)
				)
			)
		)
		(property "Device Type" "R402H16"
			(at 0.064008 -5.517896 90)
			(unlocked yes)
			(layer "F.Fab")
			(hide yes)
			(effects
				(font
					(size 1.016 1.016)
					(thickness 0.1524)
				)
			)
		)
		(duplicate_pad_numbers_are_jumpers no)
		(fp_line
			(start 0.508 -0.9398)
			(end -0.508 -0.9398)
			(stroke
				(width 0.1524)
				(type default)
			)
			(layer "F.SilkS")
		)
		(fp_line
			(start -0.508 -0.9398)
			(end -0.508 0.9398)
			(stroke
				(width 0.1524)
				(type default)
			)
			(layer "F.SilkS")
		)
		(fp_rect
			(start -0.508 0.9398)
			(end 0.508 -0.9398)
			(stroke
				(width 0)
				(type default)
			)
			(fill no)
			(layer "F.CrtYd")
		)
		(fp_rect
			(start -0.508 0.9398)
			(end 0.508 -0.9398)
			(stroke
				(width 0)
				(type default)
			)
			(fill no)
			(layer "F.Fab")
		)
		(pad "1" smd custom
			(at 0 -0.4445 90)
			(size 0.1397 0.1397)
			(layers "F.Cu" "F.Mask" "F.Paste")
			(net "P3V3_STBY")
			(options
				(clearance outline)
				(anchor circle)
			)
			(primitives
				(gr_poly
					(pts
						(arc
							(start -0.1778 -0.2794)
							(mid -0.249642 -0.249642)
							(end -0.2794 -0.1778)
						)
						(arc
							(start -0.2794 0.1778)
							(mid -0.249642 0.249642)
							(end -0.1778 0.2794)
						)
						(arc
							(start 0.1778 0.2794)
							(mid 0.249642 0.249642)
							(end 0.2794 0.1778)
						)
						(arc
							(start 0.2794 -0.1778)
							(mid 0.249642 -0.249642)
							(end 0.1778 -0.2794)
						)
					)
					(width 0)
					(fill yes)
				)
			)
		)
		(pad "2" smd custom
			(at 0 0.4445 90)
			(size 0.1397 0.1397)
			(layers "F.Cu" "F.Mask" "F.Paste")
			(net "CFG_SEL1")
			(options
				(clearance outline)
				(anchor circle)
			)
			(primitives
				(gr_poly
					(pts
						(arc
							(start -0.1778 -0.2794)
							(mid -0.249642 -0.249642)
							(end -0.2794 -0.1778)
						)
						(arc
							(start -0.2794 0.1778)
							(mid -0.249642 0.249642)
							(end -0.1778 0.2794)
						)
						(arc
							(start 0.1778 0.2794)
							(mid 0.249642 0.249642)
							(end 0.2794 0.1778)
						)
						(arc
							(start 0.2794 -0.1778)
							(mid 0.249642 -0.249642)
							(end 0.1778 -0.2794)
						)
					)
					(width 0)
					(fill yes)
				)
			)
		)
	)
	(footprint ""
		(layer "F.Cu")
		(at 205.301596 -119.272812 90)
		(property "Reference" "PR9015"
			(at 0 0 90)
			(layer "F.SilkS")
			(hide yes)
			(effects
				(font
					(size 1.27 1.27)
				)
			)
		)
		(property "Value" "0R2J-2-GP"
			(at 0.064008 -3.993896 90)
			(unlocked yes)
			(layer "F.Fab")
			(hide yes)
			(effects
				(font
					(size 1.016 1.016)
					(thickness 0.1524)
				)
			)
		)
		(property "Device Type" "R402H16"
			(at 0.064008 -5.517896 90)
			(unlocked yes)
			(layer "F.Fab")
			(hide yes)
			(effects
				(font
					(size 1.016 1.016)
					(thickness 0.1524)
				)
			)
		)
		(duplicate_pad_numbers_are_jumpers no)
		(fp_line
			(start 0.508 -0.9398)
			(end -0.508 -0.9398)
			(stroke
				(width 0.1524)
				(type default)
			)
			(layer "F.SilkS")
		)
		(fp_line
			(start -0.508 -0.9398)
			(end -0.508 0.9398)
			(stroke
				(width 0.1524)
				(type default)
			)
			(layer "F.SilkS")
		)
		(fp_rect
			(start -0.508 0.9398)
			(end 0.508 -0.9398)
			(stroke
				(width 0)
				(type default)
			)
			(fill no)
			(layer "F.CrtYd")
		)
		(fp_rect
			(start -0.508 0.9398)
			(end 0.508 -0.9398)
			(stroke
				(width 0)
				(type default)
			)
			(fill no)
			(layer "F.Fab")
		)
		(pad "1" smd custom
			(at 0 -0.4445 90)
			(size 0.1397 0.1397)
			(layers "F.Cu" "F.Mask" "F.Paste")
			(net "P1V5_E_VO")
			(options
				(clearance outline)
				(anchor circle)
			)
			(primitives
				(gr_poly
					(pts
						(arc
							(start -0.1778 -0.2794)
							(mid -0.249642 -0.249642)
							(end -0.2794 -0.1778)
						)
						(arc
							(start -0.2794 0.1778)
							(mid -0.249642 0.249642)
							(end -0.1778 0.2794)
						)
						(arc
							(start 0.1778 0.2794)
							(mid 0.249642 0.249642)
							(end 0.2794 0.1778)
						)
						(arc
							(start 0.2794 -0.1778)
							(mid 0.249642 -0.249642)
							(end 0.1778 -0.2794)
						)
					)
					(width 0)
					(fill yes)
				)
			)
		)
		(pad "2" smd custom
			(at 0 0.4445 90)
			(size 0.1397 0.1397)
			(layers "F.Cu" "F.Mask" "F.Paste")
			(net "P1V5_E_CC_R")
			(options
				(clearance outline)
				(anchor circle)
			)
			(primitives
				(gr_poly
					(pts
						(arc
							(start -0.1778 -0.2794)
							(mid -0.249642 -0.249642)
							(end -0.2794 -0.1778)
						)
						(arc
							(start -0.2794 0.1778)
							(mid -0.249642 0.249642)
							(end -0.1778 0.2794)
						)
						(arc
							(start 0.1778 0.2794)
							(mid 0.249642 0.249642)
							(end 0.2794 0.1778)
						)
						(arc
							(start 0.2794 -0.1778)
							(mid 0.249642 -0.249642)
							(end 0.1778 -0.2794)
						)
					)
					(width 0)
					(fill yes)
				)
			)
		)
	)
	(footprint ""
		(layer "F.Cu")
		(at 308.737 -216.789)
		(property "Reference" "R658"
			(at 0 0 0)
			(layer "F.SilkS")
			(hide yes)
			(effects
				(font
					(size 1.27 1.27)
				)
			)
		)
		(property "Value" "0R2J-2-GP"
			(at 0.064008 -3.993896 0)
			(unlocked yes)
			(layer "F.Fab")
			(hide yes)
			(effects
				(font
					(size 1.016 1.016)
					(thickness 0.1524)
				)
			)
		)
		(property "Device Type" "R402H16"
			(at 0.064008 -5.517896 0)
			(unlocked yes)
			(layer "F.Fab")
			(hide yes)
			(effects
				(font
					(size 1.016 1.016)
					(thickness 0.1524)
				)
			)
		)
		(duplicate_pad_numbers_are_jumpers no)
		(fp_line
			(start -0.508 -0.9398)
			(end -0.508 0.9398)
			(stroke
				(width 0.1524)
				(type default)
			)
			(layer "F.SilkS")
		)
		(fp_line
			(start 0.508 -0.9398)
			(end -0.508 -0.9398)
			(stroke
				(width 0.1524)
				(type default)
			)
			(layer "F.SilkS")
		)
		(fp_rect
			(start -0.508 0.9398)
			(end 0.508 -0.9398)
			(stroke
				(width 0)
				(type default)
			)
			(fill no)
			(layer "F.CrtYd")
		)
		(fp_rect
			(start -0.508 0.9398)
			(end 0.508 -0.9398)
			(stroke
				(width 0)
				(type default)
			)
			(fill no)
			(layer "F.Fab")
		)
		(pad "1" smd custom
			(at 0 -0.4445)
			(size 0.1397 0.1397)
			(layers "F.Cu" "F.Mask" "F.Paste")
			(net "BMC_DEBUG_OE_2_N")
			(options
				(clearance outline)
				(anchor circle)
			)
			(primitives
				(gr_poly
					(pts
						(arc
							(start -0.1778 -0.2794)
							(mid -0.249642 -0.249642)
							(end -0.2794 -0.1778)
						)
						(arc
							(start -0.2794 0.1778)
							(mid -0.249642 0.249642)
							(end -0.1778 0.2794)
						)
						(arc
							(start 0.1778 0.2794)
							(mid 0.249642 0.249642)
							(end 0.2794 0.1778)
						)
						(arc
							(start 0.2794 -0.1778)
							(mid 0.249642 -0.249642)
							(end 0.1778 -0.2794)
						)
					)
					(width 0)
					(fill yes)
				)
			)
		)
		(pad "2" smd custom
			(at 0 0.4445)
			(size 0.1397 0.1397)
			(layers "F.Cu" "F.Mask" "F.Paste")
			(net "BMC0_TACH10")
			(options
				(clearance outline)
				(anchor circle)
			)
			(primitives
				(gr_poly
					(pts
						(arc
							(start -0.1778 -0.2794)
							(mid -0.249642 -0.249642)
							(end -0.2794 -0.1778)
						)
						(arc
							(start -0.2794 0.1778)
							(mid -0.249642 0.249642)
							(end -0.1778 0.2794)
						)
						(arc
							(start 0.1778 0.2794)
							(mid 0.249642 0.249642)
							(end 0.2794 0.1778)
						)
						(arc
							(start 0.2794 -0.1778)
							(mid 0.249642 -0.249642)
							(end 0.1778 -0.2794)
						)
					)
					(width 0)
					(fill yes)
				)
			)
		)
	)
	(footprint ""
		(layer "F.Cu")
		(at 95.89897 -93.091 -90)
		(property "Reference" "SR814"
			(at 0 0 270)
			(layer "F.SilkS")
			(hide yes)
			(effects
				(font
					(size 1.27 1.27)
				)
			)
		)
		(property "Value" "1KR2F-3-GP"
			(at 0.064008 -3.993896 270)
			(unlocked yes)
			(layer "F.Fab")
			(hide yes)
			(effects
				(font
					(size 1.016 1.016)
					(thickness 0.1524)
				)
			)
		)
		(property "Device Type" "R402H16"
			(at 0.064008 -5.517896 270)
			(unlocked yes)
			(layer "F.Fab")
			(hide yes)
			(effects
				(font
					(size 1.016 1.016)
					(thickness 0.1524)
				)
			)
		)
		(duplicate_pad_numbers_are_jumpers no)
		(fp_line
			(start -0.508 -0.9398)
			(end -0.508 0.9398)
			(stroke
				(width 0.1524)
				(type default)
			)
			(layer "F.SilkS")
		)
		(fp_line
			(start 0.508 -0.9398)
			(end -0.508 -0.9398)
			(stroke
				(width 0.1524)
				(type default)
			)
			(layer "F.SilkS")
		)
		(fp_rect
			(start -0.508 0.9398)
			(end 0.508 -0.9398)
			(stroke
				(width 0)
				(type default)
			)
			(fill no)
			(layer "F.CrtYd")
		)
		(fp_rect
			(start -0.508 0.9398)
			(end 0.508 -0.9398)
			(stroke
				(width 0)
				(type default)
			)
			(fill no)
			(layer "F.Fab")
		)
		(pad "1" smd custom
			(at 0 -0.4445 270)
			(size 0.1397 0.1397)
			(layers "F.Cu" "F.Mask" "F.Paste")
			(net "LSI_SCAN_ENABLE")
			(options
				(clearance outline)
				(anchor circle)
			)
			(primitives
				(gr_poly
					(pts
						(arc
							(start -0.1778 -0.2794)
							(mid -0.249642 -0.249642)
							(end -0.2794 -0.1778)
						)
						(arc
							(start -0.2794 0.1778)
							(mid -0.249642 0.249642)
							(end -0.1778 0.2794)
						)
						(arc
							(start 0.1778 0.2794)
							(mid 0.249642 0.249642)
							(end 0.2794 0.1778)
						)
						(arc
							(start 0.2794 -0.1778)
							(mid 0.249642 -0.249642)
							(end 0.1778 -0.2794)
						)
					)
					(width 0)
					(fill yes)
				)
			)
		)
		(pad "2" smd custom
			(at 0 0.4445 270)
			(size 0.1397 0.1397)
			(layers "F.Cu" "F.Mask" "F.Paste")
			(net "P1V8_E")
			(options
				(clearance outline)
				(anchor circle)
			)
			(primitives
				(gr_poly
					(pts
						(arc
							(start -0.1778 -0.2794)
							(mid -0.249642 -0.249642)
							(end -0.2794 -0.1778)
						)
						(arc
							(start -0.2794 0.1778)
							(mid -0.249642 0.249642)
							(end -0.1778 0.2794)
						)
						(arc
							(start 0.1778 0.2794)
							(mid 0.249642 0.249642)
							(end 0.2794 0.1778)
						)
						(arc
							(start 0.2794 -0.1778)
							(mid 0.249642 -0.249642)
							(end 0.1778 -0.2794)
						)
					)
					(width 0)
					(fill yes)
				)
			)
		)
	)
	(footprint ""
		(layer "F.Cu")
		(at 113.792 -29.083 -90)
		(property "Reference" "SR670"
			(at 0 0 270)
			(layer "F.SilkS")
			(hide yes)
			(effects
				(font
					(size 1.27 1.27)
				)
			)
		)
		(property "Value" "4K7R2F-GP"
			(at 0.064008 -3.993896 270)
			(unlocked yes)
			(layer "F.Fab")
			(hide yes)
			(effects
				(font
					(size 1.016 1.016)
					(thickness 0.1524)
				)
			)
		)
		(property "Device Type" "R402H16"
			(at 0.064008 -5.517896 270)
			(unlocked yes)
			(layer "F.Fab")
			(hide yes)
			(effects
				(font
					(size 1.016 1.016)
					(thickness 0.1524)
				)
			)
		)
		(duplicate_pad_numbers_are_jumpers no)
		(fp_line
			(start -0.508 -0.9398)
			(end -0.508 0.9398)
			(stroke
				(width 0.1524)
				(type default)
			)
			(layer "F.SilkS")
		)
		(fp_line
			(start 0.508 -0.9398)
			(end -0.508 -0.9398)
			(stroke
				(width 0.1524)
				(type default)
			)
			(layer "F.SilkS")
		)
		(fp_rect
			(start -0.508 0.9398)
			(end 0.508 -0.9398)
			(stroke
				(width 0)
				(type default)
			)
			(fill no)
			(layer "F.CrtYd")
		)
		(fp_rect
			(start -0.508 0.9398)
			(end 0.508 -0.9398)
			(stroke
				(width 0)
				(type default)
			)
			(fill no)
			(layer "F.Fab")
		)
		(pad "1" smd custom
			(at 0 -0.4445 270)
			(size 0.1397 0.1397)
			(layers "F.Cu" "F.Mask" "F.Paste")
			(net "P1V8_C")
			(options
				(clearance outline)
				(anchor circle)
			)
			(primitives
				(gr_poly
					(pts
						(arc
							(start -0.1778 -0.2794)
							(mid -0.249642 -0.249642)
							(end -0.2794 -0.1778)
						)
						(arc
							(start -0.2794 0.1778)
							(mid -0.249642 0.249642)
							(end -0.1778 0.2794)
						)
						(arc
							(start 0.1778 0.2794)
							(mid 0.249642 0.249642)
							(end 0.2794 0.1778)
						)
						(arc
							(start 0.2794 -0.1778)
							(mid 0.249642 -0.249642)
							(end 0.1778 -0.2794)
						)
					)
					(width 0)
					(fill yes)
				)
			)
		)
		(pad "2" smd custom
			(at 0 0.4445 270)
			(size 0.1397 0.1397)
			(layers "F.Cu" "F.Mask" "F.Paste")
			(net "SYS_HALT0#")
			(options
				(clearance outline)
				(anchor circle)
			)
			(primitives
				(gr_poly
					(pts
						(arc
							(start -0.1778 -0.2794)
							(mid -0.249642 -0.249642)
							(end -0.2794 -0.1778)
						)
						(arc
							(start -0.2794 0.1778)
							(mid -0.249642 0.249642)
							(end -0.1778 0.2794)
						)
						(arc
							(start 0.1778 0.2794)
							(mid 0.249642 0.249642)
							(end 0.2794 0.1778)
						)
						(arc
							(start 0.2794 -0.1778)
							(mid 0.249642 -0.249642)
							(end 0.1778 -0.2794)
						)
					)
					(width 0)
					(fill yes)
				)
			)
		)
	)
	(footprint ""
		(layer "F.Cu")
		(at 164.211 -111.76 90)
		(property "Reference" "PR151"
			(at 0 0 90)
			(layer "F.SilkS")
			(hide yes)
			(effects
				(font
					(size 1.27 1.27)
				)
			)
		)
		(property "Value" "100KR2F-L1-GP"
			(at 0.064008 -3.993896 90)
			(unlocked yes)
			(layer "F.Fab")
			(hide yes)
			(effects
				(font
					(size 1.016 1.016)
					(thickness 0.1524)
				)
			)
		)
		(property "Device Type" "R402H16"
			(at 0.064008 -5.517896 90)
			(unlocked yes)
			(layer "F.Fab")
			(hide yes)
			(effects
				(font
					(size 1.016 1.016)
					(thickness 0.1524)
				)
			)
		)
		(duplicate_pad_numbers_are_jumpers no)
		(fp_line
			(start 0.508 -0.9398)
			(end -0.508 -0.9398)
			(stroke
				(width 0.1524)
				(type default)
			)
			(layer "F.SilkS")
		)
		(fp_line
			(start -0.508 -0.9398)
			(end -0.508 0.9398)
			(stroke
				(width 0.1524)
				(type default)
			)
			(layer "F.SilkS")
		)
		(fp_rect
			(start -0.508 0.9398)
			(end 0.508 -0.9398)
			(stroke
				(width 0)
				(type default)
			)
			(fill no)
			(layer "F.CrtYd")
		)
		(fp_rect
			(start -0.508 0.9398)
			(end 0.508 -0.9398)
			(stroke
				(width 0)
				(type default)
			)
			(fill no)
			(layer "F.Fab")
		)
		(pad "1" smd custom
			(at 0 -0.4445 90)
			(size 0.1397 0.1397)
			(layers "F.Cu" "F.Mask" "F.Paste")
			(net "P12V")
			(options
				(clearance outline)
				(anchor circle)
			)
			(primitives
				(gr_poly
					(pts
						(arc
							(start -0.1778 -0.2794)
							(mid -0.249642 -0.249642)
							(end -0.2794 -0.1778)
						)
						(arc
							(start -0.2794 0.1778)
							(mid -0.249642 0.249642)
							(end -0.1778 0.2794)
						)
						(arc
							(start 0.1778 0.2794)
							(mid 0.249642 0.249642)
							(end 0.2794 0.1778)
						)
						(arc
							(start 0.2794 -0.1778)
							(mid 0.249642 -0.249642)
							(end 0.1778 -0.2794)
						)
					)
					(width 0)
					(fill yes)
				)
			)
		)
		(pad "2" smd custom
			(at 0 0.4445 90)
			(size 0.1397 0.1397)
			(layers "F.Cu" "F.Mask" "F.Paste")
			(net "P0V9_E_EN")
			(options
				(clearance outline)
				(anchor circle)
			)
			(primitives
				(gr_poly
					(pts
						(arc
							(start -0.1778 -0.2794)
							(mid -0.249642 -0.249642)
							(end -0.2794 -0.1778)
						)
						(arc
							(start -0.2794 0.1778)
							(mid -0.249642 0.249642)
							(end -0.1778 0.2794)
						)
						(arc
							(start 0.1778 0.2794)
							(mid 0.249642 0.249642)
							(end 0.2794 0.1778)
						)
						(arc
							(start 0.2794 -0.1778)
							(mid 0.249642 -0.249642)
							(end 0.1778 -0.2794)
						)
					)
					(width 0)
					(fill yes)
				)
			)
		)
	)
)
